# BASEBOARD_FAB2 (Tioga Pass) — schematic netlist excerpt (pin names and nets, part order shuffled) for the footprints in the layout excerpt that follows; sources: Cadence DE-HDL packaged netlist, KiCad conversion of Wiwynn_Tioga_Pass_MB.brd

EU7G2  IR354XX  IR35411 IC  pkg SM  page 216
  VOS  = PVDDQ_ABC
  LGND  = GND
  VCC  = VR_PVDDQ_ABC_PH1_VCIN
  VDRV  = P5V_STBY
  PGND(0)  = GND
  GL(0)  = TP_PVDDQ_ABC_PH1_GL_0
  PGND(1)  = GND
  SW  = VR_PVDDQ_ABC_PH1_SW
  VIN(0)  = VR_FET_SW_P12V_STBY_PVDDQ_ABC
  VIN(1)  = VR_FET_SW_P12V_STBY_PVDDQ_ABC
  NC  = NC
  PHASE  = VR_PVDDQ_ABC_PH1_PHASE
  BOOST  = VR_PVDDQ_ABC_PH1_BOOT_R
  PWM  = VR_PVDDQ_ABC_PWM1
  EN  = P5V_STBY
  TOUT_FLT  = A_TSENSE_PVDDQ_ABC
  OCSET  = VR_PVDDQ_ABC_PH1_OCSET
  IOUT  = ISENSE_PVDDQ_ABC_PH1_IMON
  REFIN  = VR_PVDDQ_ABC_AIREF1
  PGND(2)  = GND
  GL(1)  = TP_PVDDQ_ABC_PH1_GL_1

(kicad_pcb
	(version 20260206)
	(generator "pcbnew")
	(generator_version "10.0")
	(general
		(thickness 1.6)
		(legacy_teardrops no)
	)
	(paper "A4")
	(title_block
		(title "Wiwynn_Tioga_Pass_MB.brd")
		(comment 1 "Tioga Pass / footprints 1009-1009 of 4770")
	)
	(layers
		(0 "F.Cu" signal "TOP")
		(4 "In1.Cu" signal "L2GND")
		(6 "In2.Cu" signal "L3")
		(8 "In3.Cu" signal "L4GND")
		(10 "In4.Cu" signal "L5")
		(12 "In5.Cu" signal "L6GND")
		(14 "In6.Cu" signal "L7VCC")
		(16 "In7.Cu" signal "L8VCC")
		(18 "In8.Cu" signal "L9GND")
		(20 "In9.Cu" signal "L10")
		(22 "In10.Cu" signal "L11GND")
		(24 "In11.Cu" signal "L12")
		(26 "In12.Cu" signal "L13GND")
		(2 "B.Cu" signal "BOTTOM")
		(9 "F.Adhes" user "F.Adhesive")
		(11 "B.Adhes" user "B.Adhesive")
		(13 "F.Paste" user "Package Geometry/Pastemask Top")
		(15 "B.Paste" user "Package Geometry/Pastemask Bottom")
		(5 "F.SilkS" user "Ref Des/Silkscreen Top")
		(7 "B.SilkS" user "Ref Des/Silkscreen Bottom")
		(1 "F.Mask" user "Board Geometry/Soldermask Top")
		(3 "B.Mask" user "Board Geometry/Soldermask Bottom")
		(17 "Dwgs.User" user "User.Drawings")
		(19 "Cmts.User" user "User.Comments")
		(21 "Eco1.User" user "User.Eco1")
		(23 "Eco2.User" user "User.Eco2")
		(25 "Edge.Cuts" user "Board Geometry/Outline")
		(27 "Margin" user)
		(31 "F.CrtYd" user "Package Geometry/Place Bound Top")
		(29 "B.CrtYd" user "Package Geometry/Place Bound Bottom")
		(35 "F.Fab" user "Ref Des/Assembly Top")
		(33 "B.Fab" user "Ref Des/Assembly Bottom")
	)
	(footprint ""
		(layer "F.Cu")
		(at 346.446094 -6.392418 -90)
		(property "Reference" "EU7G2"
			(at -5.112512 -1.254506 0)
			(unlocked yes)
			(layer "F.SilkS")
			(effects
				(font
					(size 0.7874 0.5842)
					(thickness 0.1524)
				)
			)
		)
		(property "Value" ""
			(at 0 0 270)
			(layer "F.Fab")
			(effects
				(font
					(size 1.27 1.27)
				)
			)
		)
		(duplicate_pad_numbers_are_jumpers no)
		(fp_line
			(start -3.0099 3.429)
			(end -3.0099 -3.5052)
			(stroke
				(width 0.1524)
				(type default)
			)
			(layer "F.SilkS")
		)
		(fp_line
			(start 2.9718 3.429)
			(end -3.0099 3.429)
			(stroke
				(width 0.1524)
				(type default)
			)
			(layer "F.SilkS")
		)
		(fp_line
			(start -3.0099 -3.5052)
			(end 2.9718 -3.5052)
			(stroke
				(width 0.1524)
				(type default)
			)
			(layer "F.SilkS")
		)
		(fp_line
			(start 2.9718 -3.5052)
			(end 2.9718 3.429)
			(stroke
				(width 0.1524)
				(type default)
			)
			(layer "F.SilkS")
		)
		(fp_circle
			(center -3.057398 -2.678684)
			(end -3.057398 -2.805684)
			(stroke
				(width 0.254)
				(type default)
			)
			(fill no)
			(layer "F.SilkS")
		)
		(fp_poly
			(pts
				(xy -2.9972 -3.4925) (xy -2.9972 -2.6924) (xy -2.1971 -3.4925)
			)
			(stroke
				(width 0)
				(type default)
			)
			(fill yes)
			(layer "F.SilkS")
		)
		(fp_poly
			(pts
				(xy -2.549906 -3.050032) (xy -2.549906 3.050032) (xy 2.549906 3.050032) (xy 2.549906 -3.050032)
			)
			(stroke
				(width 0)
				(type default)
			)
			(fill no)
			(layer "F.CrtYd")
		)
		(fp_line
			(start -2.549906 3.050032)
			(end -2.549906 -3.050032)
			(stroke
				(width 0.1)
				(type default)
			)
			(layer "F.Fab")
		)
		(fp_line
			(start 2.549906 3.050032)
			(end -2.549906 3.050032)
			(stroke
				(width 0.1)
				(type default)
			)
			(layer "F.Fab")
		)
		(fp_line
			(start -2.549906 -3.050032)
			(end 2.549906 -3.050032)
			(stroke
				(width 0.1)
				(type default)
			)
			(layer "F.Fab")
		)
		(fp_line
			(start 2.549906 -3.050032)
			(end 2.549906 3.050032)
			(stroke
				(width 0.1)
				(type default)
			)
			(layer "F.Fab")
		)
		(fp_circle
			(center -3.057398 -2.678684)
			(end -3.057398 -2.805684)
			(stroke
				(width 0.254)
				(type default)
			)
			(fill no)
			(layer "F.Fab")
		)
		(pad "1" smd rect
			(at -2.39522 -2.279904 270)
			(size 0.7112 0.254)
			(layers "F.Cu" "F.Mask" "F.Paste")
			(net "PVDDQ_ABC")
		)
		(pad "2" smd rect
			(at -2.39522 -1.83007 270)
			(size 0.7112 0.254)
			(layers "F.Cu" "F.Mask" "F.Paste")
			(net "GND")
		)
		(pad "3" smd rect
			(at -2.39522 -1.379982 270)
			(size 0.7112 0.254)
			(layers "F.Cu" "F.Mask" "F.Paste")
			(net "VR_PVDDQ_ABC_PH1_VCIN")
		)
		(pad "4" smd rect
			(at -2.39522 -0.929894 270)
			(size 0.7112 0.254)
			(layers "F.Cu" "F.Mask" "F.Paste")
			(net "P5V_STBY")
		)
		(pad "5" smd rect
			(at -2.39522 -0.48006 270)
			(size 0.7112 0.254)
			(layers "F.Cu" "F.Mask" "F.Paste")
			(net "GND")
		)
		(pad "6" smd rect
			(at -2.39522 -0.029972 270)
			(size 0.7112 0.254)
			(layers "F.Cu" "F.Mask" "F.Paste")
			(net "TP_PVDDQ_ABC_PH1_GL_0")
		)
		(pad "7" smd custom
			(at 0.016764 1.145032 270)
			(size 0.53975 0.53975)
			(layers "F.Cu" "F.Mask" "F.Paste")
			(net "GND")
			(options
				(clearance outline)
				(anchor circle)
			)
			(primitives
				(gr_poly
					(pts
						(xy -2.7051 1.0795) (xy -2.7051 -0.3683) (xy -0.9271 -0.3683) (xy -0.9271 -1.0795) (xy 2.7051 -1.0795)
						(xy 2.7051 1.0795)
					)
					(width 0)
					(fill yes)
				)
			)
		)
		(pad "10" smd rect
			(at -0.008382 2.874772 270)
			(size 4.3434 0.6096)
			(layers "F.Cu" "F.Mask" "F.Paste")
			(net "VR_PVDDQ_ABC_PH1_SW")
		)
		(pad "25" smd rect
			(at 1.548384 -1.283208 270)
			(size 2.3368 2.0066)
			(layers "F.Cu" "F.Mask" "F.Paste")
			(net "VR_FET_SW_P12V_STBY_PVDDQ_ABC")
		)
		(pad "30" smd rect
			(at 2.050034 -2.895092 270)
			(size 0.254 0.7112)
			(layers "F.Cu" "F.Mask" "F.Paste")
			(net "VR_FET_SW_P12V_STBY_PVDDQ_ABC")
		)
		(pad "31" smd rect
			(at 1.599946 -2.895092 270)
			(size 0.254 0.7112)
			(layers "F.Cu" "F.Mask" "F.Paste")
			(net "Net_368")
		)
		(pad "32" smd rect
			(at 1.150112 -2.895092 270)
			(size 0.254 0.7112)
			(layers "F.Cu" "F.Mask" "F.Paste")
			(net "VR_PVDDQ_ABC_PH1_PHASE")
		)
		(pad "33" smd rect
			(at 0.700024 -2.895092 270)
			(size 0.254 0.7112)
			(layers "F.Cu" "F.Mask" "F.Paste")
			(net "VR_PVDDQ_ABC_PH1_BOOT_R")
		)
		(pad "34" smd rect
			(at 0.249936 -2.895092 270)
			(size 0.254 0.7112)
			(layers "F.Cu" "F.Mask" "F.Paste")
			(net "VR_PVDDQ_ABC_PWM1")
		)
		(pad "35" smd rect
			(at -0.199898 -2.895092 270)
			(size 0.254 0.7112)
			(layers "F.Cu" "F.Mask" "F.Paste")
			(net "P5V_STBY")
		)
		(pad "36" smd rect
			(at -0.649986 -2.895092 270)
			(size 0.254 0.7112)
			(layers "F.Cu" "F.Mask" "F.Paste")
			(net "A_TSENSE_PVDDQ_ABC")
		)
		(pad "37" smd rect
			(at -1.100074 -2.895092 270)
			(size 0.254 0.7112)
			(layers "F.Cu" "F.Mask" "F.Paste")
			(net "VR_PVDDQ_ABC_PH1_OCSET")
		)
		(pad "38" smd rect
			(at -1.549908 -2.895092 270)
			(size 0.254 0.7112)
			(layers "F.Cu" "F.Mask" "F.Paste")
			(net "ISENSE_PVDDQ_ABC_PH1_IMON")
		)
		(pad "39" smd rect
			(at -1.999996 -2.895092 270)
			(size 0.254 0.7112)
			(layers "F.Cu" "F.Mask" "F.Paste")
			(net "VR_PVDDQ_ABC_AIREF1")
		)
		(pad "40" smd rect
			(at -0.871728 -1.283208 270)
			(size 1.8034 2.0066)
			(layers "F.Cu" "F.Mask" "F.Paste")
			(net "GND")
		)
		(pad "41" smd rect
			(at -1.533906 0.247904 270)
			(size 0.508 0.3556)
			(layers "F.Cu" "F.Mask" "F.Paste")
			(net "TP_PVDDQ_ABC_PH1_GL_1")
		)
	)
)
